# BASEBOARD_FAB2 (Tioga Pass) — schematic netlist excerpt (pin names and nets, part order shuffled) for the footprints in the layout excerpt that follows; sources: Cadence DE-HDL packaged netlist, KiCad conversion of Wiwynn_Tioga_Pass_MB.brd

R6T4  RES  10.0 1% CHIP  pkg 0402  page 99 : A = SMB_DDR_GHJ_SDA_G_R ; B = SMB_DDR_GHJ_SDA_G
C5G92  CAP_A  22.0UF 4V 20% X6S  pkg 0603V  page 243 : A = PVDDQ_GHJ ; B = GND
R25W50  120R2F-GP  1%  pkg RCL_GP  page 151 : \1\ = BMC_M_A12 ; \2\ = P1V2_AUX_BMC

(kicad_pcb
	(version 20260206)
	(generator "pcbnew")
	(generator_version "10.0")
	(general
		(thickness 1.6)
		(legacy_teardrops no)
	)
	(paper "A4")
	(title_block
		(title "Wiwynn_Tioga_Pass_MB.brd")
		(comment 1 "Tioga Pass / footprints 4176-4178 of 4770")
	)
	(layers
		(0 "F.Cu" signal "TOP")
		(4 "In1.Cu" signal "L2GND")
		(6 "In2.Cu" signal "L3")
		(8 "In3.Cu" signal "L4GND")
		(10 "In4.Cu" signal "L5")
		(12 "In5.Cu" signal "L6GND")
		(14 "In6.Cu" signal "L7VCC")
		(16 "In7.Cu" signal "L8VCC")
		(18 "In8.Cu" signal "L9GND")
		(20 "In9.Cu" signal "L10")
		(22 "In10.Cu" signal "L11GND")
		(24 "In11.Cu" signal "L12")
		(26 "In12.Cu" signal "L13GND")
		(2 "B.Cu" signal "BOTTOM")
		(9 "F.Adhes" user "F.Adhesive")
		(11 "B.Adhes" user "B.Adhesive")
		(13 "F.Paste" user "Package Geometry/Pastemask Top")
		(15 "B.Paste" user "Package Geometry/Pastemask Bottom")
		(5 "F.SilkS" user "Ref Des/Silkscreen Top")
		(7 "B.SilkS" user "Ref Des/Silkscreen Bottom")
		(1 "F.Mask" user "Board Geometry/Soldermask Top")
		(3 "B.Mask" user "Board Geometry/Soldermask Bottom")
		(17 "Dwgs.User" user "User.Drawings")
		(19 "Cmts.User" user "User.Comments")
		(21 "Eco1.User" user "User.Eco1")
		(23 "Eco2.User" user "User.Eco2")
		(25 "Edge.Cuts" user "Board Geometry/Outline")
		(27 "Margin" user)
		(31 "F.CrtYd" user "Package Geometry/Place Bound Top")
		(29 "B.CrtYd" user "Package Geometry/Place Bound Bottom")
		(35 "F.Fab" user "Ref Des/Assembly Top")
		(33 "B.Fab" user "Ref Des/Assembly Bottom")
	)
	(footprint ""
		(layer "B.Cu")
		(at 169.770552 -22.654006 -90)
		(property "Reference" "R6T4"
			(at 0 0 90)
			(layer "B.SilkS")
			(hide yes)
			(effects
				(font
					(size 1.27 1.27)
				)
				(justify mirror)
			)
		)
		(property "Value" ""
			(at 0 0 90)
			(layer "B.Fab")
			(effects
				(font
					(size 1.27 1.27)
				)
				(justify mirror)
			)
		)
		(duplicate_pad_numbers_are_jumpers no)
		(fp_poly
			(pts
				(xy 0.2794 -0.1016) (xy -0.2794 -0.1016) (xy -0.2794 0.9906) (xy 0.2794 0.9906)
			)
			(stroke
				(width 0)
				(type default)
			)
			(fill no)
			(layer "B.CrtYd")
		)
		(fp_line
			(start -0.2794 0.9906)
			(end -0.2794 -0.1016)
			(stroke
				(width 0.1)
				(type default)
			)
			(layer "B.Fab")
		)
		(fp_line
			(start 0.2794 0.9906)
			(end -0.2794 0.9906)
			(stroke
				(width 0.1)
				(type default)
			)
			(layer "B.Fab")
		)
		(fp_line
			(start -0.2794 -0.1016)
			(end 0.2794 -0.1016)
			(stroke
				(width 0.1)
				(type default)
			)
			(layer "B.Fab")
		)
		(fp_line
			(start 0.2794 -0.1016)
			(end 0.2794 0.9906)
			(stroke
				(width 0.1)
				(type default)
			)
			(layer "B.Fab")
		)
		(pad "1" smd rect
			(at 0 0 90)
			(size 0.508 0.508)
			(layers "B.Cu" "B.Mask" "B.Paste")
			(net "SMB_DDR_GHJ_SDA_G_R")
		)
		(pad "2" smd rect
			(at 0 0.889 90)
			(size 0.508 0.508)
			(layers "B.Cu" "B.Mask" "B.Paste")
			(net "SMB_DDR_GHJ_SDA_G")
		)
		(zone
			(layer "B.Cu")
			(hatch none 0.5)
			(connect_pads
				(clearance 0)
			)
			(min_thickness 0.25)
			(keepout
				(tracks not_allowed)
				(vias allowed)
				(pads allowed)
				(copperpour not_allowed)
				(footprints allowed)
			)
			(placement
				(enabled no)
				(sheetname "")
			)
			(fill
				(thermal_gap 0.5)
				(thermal_bridge_width 0.5)
				(island_removal_mode 0)
			)
			(polygon
				(pts
					(xy 169.135552 -22.400006) (xy 169.135552 -22.908006) (xy 169.516552 -22.908006) (xy 169.516552 -22.400006)
				)
			)
		)
		(zone
			(layer "B.Cu")
			(hatch none 0.5)
			(connect_pads
				(clearance 0)
			)
			(min_thickness 0.25)
			(keepout
				(tracks allowed)
				(vias not_allowed)
				(pads allowed)
				(copperpour not_allowed)
				(footprints allowed)
			)
			(placement
				(enabled no)
				(sheetname "")
			)
			(fill
				(thermal_gap 0.5)
				(thermal_bridge_width 0.5)
				(island_removal_mode 0)
			)
			(polygon
				(pts
					(xy 169.516552 -22.400006) (xy 169.516552 -22.908006) (xy 169.135552 -22.908006) (xy 169.135552 -22.400006)
				)
			)
		)
	)
	(footprint ""
		(layer "B.Cu")
		(at 111.000032 -3.3528 90)
		(property "Reference" "C5G92"
			(at -1.14681 0.76708 180)
			(unlocked yes)
			(layer "B.SilkS")
			(effects
				(font
					(size 0.7874 0.5842)
					(thickness 0.1524)
				)
				(justify mirror)
			)
		)
		(property "Value" ""
			(at 0 0 90)
			(layer "B.Fab")
			(effects
				(font
					(size 1.27 1.27)
				)
				(justify mirror)
			)
		)
		(duplicate_pad_numbers_are_jumpers no)
		(fp_rect
			(start -0.4953 -0.2032)
			(end 0.4953 1.6002)
			(stroke
				(width 0)
				(type default)
			)
			(fill no)
			(layer "B.CrtYd")
		)
		(fp_line
			(start 0.4953 -0.2032)
			(end -0.4953 -0.2032)
			(stroke
				(width 0.1)
				(type default)
			)
			(layer "B.Fab")
		)
		(fp_line
			(start -0.4953 -0.2032)
			(end -0.4953 1.6002)
			(stroke
				(width 0.1)
				(type default)
			)
			(layer "B.Fab")
		)
		(fp_line
			(start 0.4953 1.6002)
			(end 0.4953 -0.2032)
			(stroke
				(width 0.1)
				(type default)
			)
			(layer "B.Fab")
		)
		(fp_line
			(start -0.4953 1.6002)
			(end 0.4953 1.6002)
			(stroke
				(width 0.1)
				(type default)
			)
			(layer "B.Fab")
		)
		(pad "1" smd rect
			(at 0 0 270)
			(size 0.762 0.889)
			(layers "B.Cu" "B.Mask" "B.Paste")
			(net "PVDDQ_GHJ")
		)
		(pad "2" smd rect
			(at 0 1.397 270)
			(size 0.762 0.889)
			(layers "B.Cu" "B.Mask" "B.Paste")
			(net "GND")
		)
		(zone
			(layer "B.Cu")
			(hatch none 0.5)
			(connect_pads
				(clearance 0)
			)
			(min_thickness 0.25)
			(keepout
				(tracks not_allowed)
				(vias allowed)
				(pads allowed)
				(copperpour not_allowed)
				(footprints allowed)
			)
			(placement
				(enabled no)
				(sheetname "")
			)
			(fill
				(thermal_gap 0.5)
				(thermal_bridge_width 0.5)
				(island_removal_mode 0)
			)
			(polygon
				(pts
					(xy 111.444532 -2.9718) (xy 111.952532 -2.9718) (xy 111.952532 -3.7338) (xy 111.444532 -3.7338)
				)
			)
		)
	)
	(footprint ""
		(layer "B.Cu")
		(at 441.119006 -43.54195 180)
		(property "Reference" "R25W50"
			(at 0 0 0)
			(layer "B.SilkS")
			(hide yes)
			(effects
				(font
					(size 1.27 1.27)
				)
				(justify mirror)
			)
		)
		(property "Value" "*"
			(at -0.064008 -4.108196 180)
			(unlocked yes)
			(layer "B.Fab")
			(hide yes)
			(effects
				(font
					(size 1.27 1.016)
					(thickness 0.1524)
				)
				(justify mirror)
			)
		)
		(property "Device Type" "120R2F-GP_RCL_GP-120R2F-GP,64.A"
			(at -0.064008 -5.632196 180)
			(unlocked yes)
			(layer "B.Fab")
			(hide yes)
			(effects
				(font
					(size 1.27 1.016)
					(thickness 0.1524)
				)
				(justify mirror)
			)
		)
		(duplicate_pad_numbers_are_jumpers no)
		(fp_line
			(start 0.508 -0.9398)
			(end 0.508 0.9398)
			(stroke
				(width 0.1524)
				(type default)
			)
			(layer "B.SilkS")
		)
		(fp_line
			(start -0.508 -0.9398)
			(end 0.508 -0.9398)
			(stroke
				(width 0.1524)
				(type default)
			)
			(layer "B.SilkS")
		)
		(fp_rect
			(start 0.508 0.9398)
			(end -0.508 -0.9398)
			(stroke
				(width 0)
				(type default)
			)
			(fill no)
			(layer "B.CrtYd")
		)
		(fp_rect
			(start 0.508 0.9398)
			(end -0.508 -0.9398)
			(stroke
				(width 0)
				(type default)
			)
			(fill no)
			(layer "B.Fab")
		)
		(pad "1" smd custom
			(at 0 -0.4445)
			(size 0.1397 0.1397)
			(layers "B.Cu" "B.Mask" "B.Paste")
			(net "BMC_M_A12")
			(options
				(clearance outline)
				(anchor circle)
			)
			(primitives
				(gr_poly
					(pts
						(arc
							(start -0.1778 0.2794)
							(mid -0.249642 0.249642)
							(end -0.2794 0.1778)
						)
						(arc
							(start -0.2794 -0.1778)
							(mid -0.249642 -0.249642)
							(end -0.1778 -0.2794)
						)
						(arc
							(start 0.1778 -0.2794)
							(mid 0.249642 -0.249642)
							(end 0.2794 -0.1778)
						)
						(arc
							(start 0.2794 0.1778)
							(mid 0.249642 0.249642)
							(end 0.1778 0.2794)
						)
					)
					(width 0)
					(fill yes)
				)
			)
		)
		(pad "2" smd custom
			(at 0 0.4445)
			(size 0.1397 0.1397)
			(layers "B.Cu" "B.Mask" "B.Paste")
			(net "P1V2_AUX_BMC")
			(options
				(clearance outline)
				(anchor circle)
			)
			(primitives
				(gr_poly
					(pts
						(arc
							(start -0.1778 0.2794)
							(mid -0.249642 0.249642)
							(end -0.2794 0.1778)
						)
						(arc
							(start -0.2794 -0.1778)
							(mid -0.249642 -0.249642)
							(end -0.1778 -0.2794)
						)
						(arc
							(start 0.1778 -0.2794)
							(mid 0.249642 -0.249642)
							(end 0.2794 -0.1778)
						)
						(arc
							(start 0.2794 0.1778)
							(mid 0.249642 0.249642)
							(end 0.1778 0.2794)
						)
					)
					(width 0)
					(fill yes)
				)
			)
		)
	)
)
